# BASEBOARD_FAB2 (Tioga Pass) — schematic netlist excerpt (pin names and nets, part order shuffled) for the footprints in the layout excerpt that follows; sources: Cadence DE-HDL packaged netlist, KiCad conversion of Wiwynn_Tioga_Pass_MB.brd

C6M5  CAP  10UF 16V 10% X6S  pkg 0805  page 234 : A = VR_FET_SW_P12V_STBY_PVPP_KLM ; B = GND
R9N2  RES  100.0 1% CHIP  pkg 0402  page 55 : A = PVCCIO_CPU1 ; B = SVID_DIO1_CPU1_R
C8E6  CAP  0.1UF 25V 10% X7R  pkg 0603LF  page 241 : A = VR_P5V_STBY_BOOT ; B = VR_P5V_STBY_PHASE

(kicad_pcb
	(version 20260206)
	(generator "pcbnew")
	(generator_version "10.0")
	(general
		(thickness 1.6)
		(legacy_teardrops no)
	)
	(paper "A4")
	(title_block
		(title "Wiwynn_Tioga_Pass_MB.brd")
		(comment 1 "Tioga Pass / footprints 101-103 of 4770")
	)
	(layers
		(0 "F.Cu" signal "TOP")
		(4 "In1.Cu" signal "L2GND")
		(6 "In2.Cu" signal "L3")
		(8 "In3.Cu" signal "L4GND")
		(10 "In4.Cu" signal "L5")
		(12 "In5.Cu" signal "L6GND")
		(14 "In6.Cu" signal "L7VCC")
		(16 "In7.Cu" signal "L8VCC")
		(18 "In8.Cu" signal "L9GND")
		(20 "In9.Cu" signal "L10")
		(22 "In10.Cu" signal "L11GND")
		(24 "In11.Cu" signal "L12")
		(26 "In12.Cu" signal "L13GND")
		(2 "B.Cu" signal "BOTTOM")
		(9 "F.Adhes" user "F.Adhesive")
		(11 "B.Adhes" user "B.Adhesive")
		(13 "F.Paste" user "Package Geometry/Pastemask Top")
		(15 "B.Paste" user "Package Geometry/Pastemask Bottom")
		(5 "F.SilkS" user "Ref Des/Silkscreen Top")
		(7 "B.SilkS" user "Ref Des/Silkscreen Bottom")
		(1 "F.Mask" user "Board Geometry/Soldermask Top")
		(3 "B.Mask" user "Board Geometry/Soldermask Bottom")
		(17 "Dwgs.User" user "User.Drawings")
		(19 "Cmts.User" user "User.Comments")
		(21 "Eco1.User" user "User.Eco1")
		(23 "Eco2.User" user "User.Eco2")
		(25 "Edge.Cuts" user "Board Geometry/Outline")
		(27 "Margin" user)
		(31 "F.CrtYd" user "Package Geometry/Place Bound Top")
		(29 "B.CrtYd" user "Package Geometry/Place Bound Bottom")
		(35 "F.Fab" user "Ref Des/Assembly Top")
		(33 "B.Fab" user "Ref Des/Assembly Bottom")
	)
	(footprint ""
		(layer "F.Cu")
		(at 394.72743 -69.65315 90)
		(property "Reference" "C8E6"
			(at 0 0 90)
			(layer "F.SilkS")
			(hide yes)
			(effects
				(font
					(size 1.27 1.27)
				)
			)
		)
		(property "Value" ""
			(at 0 0 90)
			(layer "F.Fab")
			(effects
				(font
					(size 1.27 1.27)
				)
			)
		)
		(duplicate_pad_numbers_are_jumpers no)
		(fp_poly
			(pts
				(xy -0.4953 -0.2032) (xy 0.4953 -0.2032) (xy 0.4953 1.6002) (xy -0.4953 1.6002)
			)
			(stroke
				(width 0)
				(type default)
			)
			(fill no)
			(layer "F.CrtYd")
		)
		(fp_line
			(start 0.4953 -0.2032)
			(end 0.4953 1.6002)
			(stroke
				(width 0.1)
				(type default)
			)
			(layer "F.Fab")
		)
		(fp_line
			(start -0.4953 -0.2032)
			(end 0.4953 -0.2032)
			(stroke
				(width 0.1)
				(type default)
			)
			(layer "F.Fab")
		)
		(fp_line
			(start 0.4953 1.6002)
			(end -0.4953 1.6002)
			(stroke
				(width 0.1)
				(type default)
			)
			(layer "F.Fab")
		)
		(fp_line
			(start -0.4953 1.6002)
			(end -0.4953 -0.2032)
			(stroke
				(width 0.1)
				(type default)
			)
			(layer "F.Fab")
		)
		(pad "1" smd rect
			(at 0 0 90)
			(size 0.762 0.889)
			(layers "F.Cu" "F.Mask" "F.Paste")
			(net "VR_P5V_STBY_BOOT")
		)
		(pad "2" smd rect
			(at 0 1.397 90)
			(size 0.762 0.889)
			(layers "F.Cu" "F.Mask" "F.Paste")
			(net "VR_P5V_STBY_PHASE")
		)
		(zone
			(layer "F.Cu")
			(hatch none 0.5)
			(connect_pads
				(clearance 0)
			)
			(min_thickness 0.25)
			(keepout
				(tracks not_allowed)
				(vias allowed)
				(pads allowed)
				(copperpour not_allowed)
				(footprints allowed)
			)
			(placement
				(enabled no)
				(sheetname "")
			)
			(fill
				(thermal_gap 0.5)
				(thermal_bridge_width 0.5)
				(island_removal_mode 0)
			)
			(polygon
				(pts
					(xy 395.17193 -69.27215) (xy 395.17193 -70.03415) (xy 395.67993 -70.03415) (xy 395.67993 -69.27215)
				)
			)
		)
	)
	(footprint ""
		(layer "F.Cu")
		(at 183.134 -132.207 90)
		(property "Reference" "C6M5"
			(at 1.47828 0.78994 0)
			(unlocked yes)
			(layer "F.SilkS")
			(effects
				(font
					(size 0.4064 0.254)
					(thickness 0.1524)
				)
			)
		)
		(property "Value" ""
			(at 0 0 90)
			(layer "F.Fab")
			(effects
				(font
					(size 1.27 1.27)
				)
			)
		)
		(duplicate_pad_numbers_are_jumpers no)
		(fp_poly
			(pts
				(xy -0.7239 -0.2159) (xy 0.7239 -0.2159) (xy 0.7239 1.9939) (xy -0.7239 1.9939)
			)
			(stroke
				(width 0)
				(type default)
			)
			(fill no)
			(layer "F.CrtYd")
		)
		(fp_line
			(start 0.7239 -0.2159)
			(end -0.7239 -0.2159)
			(stroke
				(width 0.1)
				(type default)
			)
			(layer "F.Fab")
		)
		(fp_line
			(start -0.7239 -0.2159)
			(end -0.7239 1.9939)
			(stroke
				(width 0.1)
				(type default)
			)
			(layer "F.Fab")
		)
		(fp_line
			(start 0.7239 1.9939)
			(end 0.7239 -0.2159)
			(stroke
				(width 0.1)
				(type default)
			)
			(layer "F.Fab")
		)
		(fp_line
			(start -0.7239 1.9939)
			(end 0.7239 1.9939)
			(stroke
				(width 0.1)
				(type default)
			)
			(layer "F.Fab")
		)
		(pad "1" smd rect
			(at 0 0 90)
			(size 1.27 1.016)
			(layers "F.Cu" "F.Mask" "F.Paste")
			(net "VR_FET_SW_P12V_STBY_PVPP_KLM")
		)
		(pad "2" smd rect
			(at 0 1.778 90)
			(size 1.27 1.016)
			(layers "F.Cu" "F.Mask" "F.Paste")
			(net "GND")
		)
		(zone
			(layer "F.Cu")
			(hatch none 0.5)
			(connect_pads
				(clearance 0)
			)
			(min_thickness 0.25)
			(keepout
				(tracks not_allowed)
				(vias allowed)
				(pads allowed)
				(copperpour not_allowed)
				(footprints allowed)
			)
			(placement
				(enabled no)
				(sheetname "")
			)
			(fill
				(thermal_gap 0.5)
				(thermal_bridge_width 0.5)
				(island_removal_mode 0)
			)
			(polygon
				(pts
					(xy 183.642 -131.572) (xy 183.642 -132.842) (xy 184.404 -132.842) (xy 184.404 -131.572)
				)
			)
		)
	)
	(footprint ""
		(layer "F.Cu")
		(at 39.330122 -106.415586 -90)
		(property "Reference" "R9N2"
			(at 0 0 270)
			(layer "F.SilkS")
			(hide yes)
			(effects
				(font
					(size 1.27 1.27)
				)
			)
		)
		(property "Value" ""
			(at 0 0 270)
			(layer "F.Fab")
			(effects
				(font
					(size 1.27 1.27)
				)
			)
		)
		(duplicate_pad_numbers_are_jumpers no)
		(fp_poly
			(pts
				(xy -0.2794 -0.1016) (xy 0.2794 -0.1016) (xy 0.2794 0.9906) (xy -0.2794 0.9906)
			)
			(stroke
				(width 0)
				(type default)
			)
			(fill no)
			(layer "F.CrtYd")
		)
		(fp_line
			(start -0.2794 0.9906)
			(end 0.2794 0.9906)
			(stroke
				(width 0.1)
				(type default)
			)
			(layer "F.Fab")
		)
		(fp_line
			(start 0.2794 0.9906)
			(end 0.2794 -0.1016)
			(stroke
				(width 0.1)
				(type default)
			)
			(layer "F.Fab")
		)
		(fp_line
			(start -0.2794 -0.1016)
			(end -0.2794 0.9906)
			(stroke
				(width 0.1)
				(type default)
			)
			(layer "F.Fab")
		)
		(fp_line
			(start 0.2794 -0.1016)
			(end -0.2794 -0.1016)
			(stroke
				(width 0.1)
				(type default)
			)
			(layer "F.Fab")
		)
		(pad "1" smd rect
			(at 0 0 270)
			(size 0.508 0.508)
			(layers "F.Cu" "F.Mask" "F.Paste")
			(net "PVCCIO_CPU1")
		)
		(pad "2" smd rect
			(at 0 0.889 270)
			(size 0.508 0.508)
			(layers "F.Cu" "F.Mask" "F.Paste")
			(net "SVID_DIO1_CPU1_R")
		)
		(zone
			(layer "F.Cu")
			(hatch none 0.5)
			(connect_pads
				(clearance 0)
			)
			(min_thickness 0.25)
			(keepout
				(tracks not_allowed)
				(vias allowed)
				(pads allowed)
				(copperpour not_allowed)
				(footprints allowed)
			)
			(placement
				(enabled no)
				(sheetname "")
			)
			(fill
				(thermal_gap 0.5)
				(thermal_bridge_width 0.5)
				(island_removal_mode 0)
			)
			(polygon
				(pts
					(xy 38.695122 -106.669586) (xy 38.695122 -106.161586) (xy 39.076122 -106.161586) (xy 39.076122 -106.669586)
				)
			)
		)
		(zone
			(layer "F.Cu")
			(hatch none 0.5)
			(connect_pads
				(clearance 0)
			)
			(min_thickness 0.25)
			(keepout
				(tracks allowed)
				(vias not_allowed)
				(pads allowed)
				(copperpour not_allowed)
				(footprints allowed)
			)
			(placement
				(enabled no)
				(sheetname "")
			)
			(fill
				(thermal_gap 0.5)
				(thermal_bridge_width 0.5)
				(island_removal_mode 0)
			)
			(polygon
				(pts
					(xy 39.076122 -106.669586) (xy 39.076122 -106.161586) (xy 38.695122 -106.161586) (xy 38.695122 -106.669586)
				)
			)
		)
	)
)
